#ISCELL
  mstr_misc dns *
  *
#ISCELL
  pure_quanta quanta_title_block_c *
  *
#CELL
  pure_quanta q_res *
  page55_i10
#ISCELL
  pure_quanta_power universal_gnd *
  page55_i11
#CELL
  pure_quanta q_xtal_4p_13bi_24gnd *
  page55_i12
#ISCELL
  pure_quanta_power universal_gnd *
  page55_i13
#ISCELL
  pure_quanta_power universal_gnd *
  page55_i14
#CELL
  pure_quanta q_cap *
  page55_i15
#ISCELL
  standard offpage *
  page55_i16
#ISCELL
  standard offpage *
  page55_i17
#ISCELL
  standard offpage *
  page55_i18
#CELL
  pure_quanta genoa_sp5 *
  page55_i182
#ISCELL
  standard offpage *
  page55_i183
#ISCELL
  standard offpage *
  page55_i185
#ISCELL
  standard offpage *
  page55_i186
#ISCELL
  standard offpage *
  page55_i187
#ISCELL
  standard offpage *
  page55_i188
#ISCELL
  standard offpage *
  page55_i189
#ISCELL
  standard offpage *
  page55_i19
#ISCELL
  standard offpage *
  page55_i190
#ISCELL
  standard offpage *
  page55_i191
#ISCELL
  standard offpage *
  page55_i192
#ISCELL
  standard offpage *
  page55_i193
#ISCELL
  pure_quanta_power universal_gnd *
  page55_i2
#ISCELL
  standard offpage *
  page55_i212
#ISCELL
  standard offpage *
  page55_i215
#ISCELL
  standard offpage *
  page55_i216
#ISCELL
  standard offpage *
  page55_i217
#ISCELL
  standard offpage *
  page55_i218
#ISCELL
  standard offpage *
  page55_i219
#ISCELL
  standard offpage *
  page55_i220
#ISCELL
  standard offpage *
  page55_i221
#ISCELL
  standard offpage *
  page55_i230
#CELL
  pure_quanta q_res *
  page55_i236
#CELL
  pure_quanta q_res *
  page55_i24
#ISCELL
  standard offpage *
  page55_i241
#ISCELL
  standard offpage *
  page55_i251
#ISCELL
  standard offpage *
  page55_i252
#ISCELL
  standard offpage *
  page55_i253
#ISCELL
  standard offpage *
  page55_i254
#ISCELL
  standard offpage *
  page55_i255
#ISCELL
  standard offpage *
  page55_i256
#CELL
  pure_quanta q_res *
  page55_i26
#ISCELL
  standard offpage *
  page55_i27
#ISCELL
  standard offpage *
  page55_i277
#ISCELL
  standard offpage *
  page55_i278
#ISCELL
  pure_quanta_power universal_power *
  page55_i291
#CELL
  pure_quanta q_res *
  page55_i292
#CELL
  pure_quanta q_res *
  page55_i296
#CELL
  pure_quanta q_res *
  page55_i297
#CELL
  pure_quanta q_res *
  page55_i298
#ISCELL
  standard offpage *
  page55_i299
#CELL
  pure_quanta q_cap *
  page55_i3
#ISCELL
  standard offpage *
  page55_i300
#ISCELL
  standard offpage *
  page55_i301
#CELL
  pure_quanta q_res *
  page55_i302
#CELL
  pure_quanta q_res *
  page55_i303
#ISCELL
  standard offpage *
  page55_i304
#ISCELL
  standard offpage *
  page55_i305
#CELL
  pure_quanta q_res *
  page55_i306
#CELL
  pure_quanta q_res *
  page55_i307
#CELL
  pure_quanta q_res *
  page55_i308
#CELL
  pure_quanta q_res *
  page55_i309
#ISCELL
  standard offpage *
  page55_i310
#ISCELL
  standard offpage *
  page55_i311
#CELL
  pure_quanta q_res *
  page55_i312
#CELL
  pure_quanta q_res *
  page55_i313
#ISCELL
  standard offpage *
  page55_i314
#ISCELL
  standard offpage *
  page55_i315
#CELL
  pure_quanta q_res *
  page55_i316
#CELL
  pure_quanta q_res *
  page55_i317
#ISCELL
  standard offpage *
  page55_i318
#ISCELL
  standard offpage *
  page55_i319
#CELL
  pure_quanta q_res *
  page55_i320
#CELL
  pure_quanta q_res *
  page55_i321
#ISCELL
  standard offpage *
  page55_i322
#ISCELL
  standard offpage *
  page55_i323
#ISCELL
  standard offpage *
  page55_i324
#ISCELL
  standard offpage *
  page55_i325
#CELL
  pure_quanta q_res *
  page55_i326
#CELL
  pure_quanta q_res *
  page55_i327
#ISCELL
  pure_quanta_power universal_gnd *
  page55_i328
#ISCELL
  pure_quanta_power universal_gnd *
  page55_i329
#CELL
  pure_quanta q_res *
  page55_i330
#CELL
  pure_quanta q_res *
  page55_i331
#ISCELL
  pure_quanta_power universal_gnd *
  page55_i332
#ISCELL
  pure_quanta_power universal_gnd *
  page55_i333
#CELL
  pure_quanta q_res *
  page55_i334
#CELL
  pure_quanta q_res *
  page55_i335
#CELL
  pure_quanta q_res *
  page55_i336
#CELL
  pure_quanta q_res *
  page55_i337
#CELL
  pure_quanta q_res *
  page55_i338
#CELL
  pure_quanta q_res *
  page55_i339
#ISCELL
  pure_quanta_power universal_gnd *
  page55_i340
#CELL
  pure_quanta q_res *
  page55_i341
#CELL
  pure_quanta q_res *
  page55_i342
#ISCELL
  pure_quanta_power universal_power *
  page55_i343
#ISCELL
  standard offpage *
  page55_i344
#ISCELL
  standard offpage *
  page55_i345
#ISCELL
  standard offpage *
  page55_i346
#ISCELL
  standard offpage *
  page55_i347
#ISCELL
  standard offpage *
  page55_i348
#ISCELL
  standard offpage *
  page55_i349
#ISCELL
  standard offpage *
  page55_i350
#ISCELL
  standard offpage *
  page55_i351
#CELL
  pure_quanta q_res *
  page55_i352
#CELL
  pure_quanta q_res *
  page55_i353
#CELL
  pure_quanta q_res *
  page55_i355
#CELL
  pure_quanta q_res *
  page55_i356
#CELL
  pure_quanta q_res *
  page55_i357
#CELL
  pure_quanta q_res *
  page55_i359
#CELL
  pure_quanta q_res *
  page55_i360
#ISCELL
  pure_quanta_power universal_power *
  page55_i361
#CELL
  pure_quanta q_res *
  page55_i362
#CELL
  pure_quanta q_res *
  page55_i363
#CELL
  pure_quanta q_res *
  page55_i364
#CELL
  pure_quanta q_res *
  page55_i365
#CELL
  pure_quanta q_res *
  page55_i366
#CELL
  pure_quanta q_res *
  page55_i367
#CELL
  pure_quanta q_res *
  page55_i368
#ISCELL
  pure_quanta_power vcc_core *
  page55_i369
#ISCELL
  standard offpage *
  page55_i370
#ISCELL
  standard offpage *
  page55_i371
#ISCELL
  standard offpage *
  page55_i373
#ISCELL
  standard offpage *
  page55_i374
#ISCELL
  standard offpage *
  page55_i375
#ISCELL
  standard offpage *
  page55_i376
#ISCELL
  standard offpage *
  page55_i377
#ISCELL
  standard offpage *
  page55_i378
#ISCELL
  standard offpage *
  page55_i379
#ISCELL
  standard offpage *
  page55_i380
#ISCELL
  standard offpage *
  page55_i381
#ISCELL
  standard offpage *
  page55_i382
#ISCELL
  standard offpage *
  page55_i383
#ISCELL
  standard offpage *
  page55_i384
#ISCELL
  standard offpage *
  page55_i385
#CELL
  pure_quanta q_res *
  page55_i386
#ISCELL
  pure_quanta_power universal_gnd *
  page55_i387
#CELL
  pure_quanta q_cap *
  page55_i388
#CELL
  pure_quanta q_res *
  page55_i389
#CELL
  pure_quanta q_res *
  page55_i390
#ISCELL
  standard offpage *
  page55_i391
#CELL
  pure_quanta q_res *
  page55_i392
#ISCELL
  pure_quanta_power universal_gnd *
  page55_i393
#CELL
  pure_quanta q_res *
  page55_i394
#ISCELL
  standard offpage *
  page55_i395
#ISCELL
  standard offpage *
  page55_i396
#CELL
  pure_quanta q_res *
  page55_i397
#ISCELL
  standard offpage *
  page55_i398
#ISCELL
  pure_quanta_power universal_gnd *
  page55_i4
#CELL
  pure_quanta q_cap *
  page55_i5
#CELL
  pure_quanta q_crystal *
  page55_i7
#ISCELL
  pure_quanta_power universal_gnd *
  page55_i8
#CELL
  pure_quanta q_cap *
  page55_i9
